# S9S_MB_2U (Grand Teton) — schematic parts with pin connectivity, parts 5880–5880 of 6093; source: Cadence DE-HDL packaged netlist (pstxprt.dat, pstxnet.dat, pstchip.dat)

U2  SOCKET4677_AZIF0045P001C01CS  SOCKET4677_AZIF0045-P001C01CS IO  pkg SOCKET4677_82X64-5XA_H466  page 13  (pins 3261-3586 of 4677)
  DY32  DDR5_SB_DQ2  BI  = M_F_CPU0_SB_DQ<2>
  DY34  DDR6_SB_ECC3  BI  = M_G_CPU0_SB_CB<3>
  DY36  DDR6_SB_DQS_DP4  BI  = M_G_CPU0_SB_DQS_DP<4>
  DY38  DDR6_SB_ECC6  BI  = M_G_CPU0_SB_CB<6>
  DY40  DDR6_SB_CS_N1  OUT  = M_G_CPU0_SB_CS_N<1>
  DY42  VSS1116  POWER  = GND
  DY44  DDR6_SB_CA3  OUT  = M_G_CPU0_SB_CA<3>
  DY47  DDR6_A_RSP1  IN  = M_G_CPU0_SA_RSP<1>
  DY49  DDR5_CLK_DN0  OUT  = M_F_CPU0_CLK_DN<0>
  DY51  DDR5_SA_CA6  OUT  = M_F_CPU0_SA_CA<6>
  DY53  DDR5_SA_DQ31  BI  = M_F_CPU0_SA_DQ<31>
  DY55  DDR5_SA_DQS_DP8  BI  = M_F_CPU0_SA_DQS_DP<8>
  DY57  DDR5_SA_DQ26  BI  = M_F_CPU0_SA_DQ<26>
  DY59  DDR6_SA_DQ23  BI  = M_G_CPU0_SA_DQ<23>
  DY61  DDR6_SA_DQS_DP7  BI  = M_G_CPU0_SA_DQS_DP<7>
  DY63  DDR6_SA_DQ18  BI  = M_G_CPU0_SA_DQ<18>
  DY65  DDR5_SA_DQ15  BI  = M_F_CPU0_SA_DQ<15>
  DY67  DDR5_SA_DQS_DP6  BI  = M_F_CPU0_SA_DQS_DP<6>
  DY69  DDR5_SA_DQ10  BI  = M_F_CPU0_SA_DQ<10>
  DY71  DDR6_SA_DQ7  BI  = M_G_CPU0_SA_DQ<7>
  DY73  DDR6_SA_DQS_DP5  BI  = M_G_CPU0_SA_DQS_DP<5>
  DY75  DDR6_SA_DQ2  BI  = M_G_CPU0_SA_DQ<2>
  DY77  VSS1269  POWER  = GND
  DY79  DDR7_SA_DQ0  BI  = M_H_CPU0_SA_DQ<0>
  DY81  UPI3_RX_DN8  IN  = GND
  DY83  UPI3_RX_DP7  IN  = GND
  DY85  VCCFA_EHV_FIVRA65  POWER  = PVCCFA_EHV_FIVRA_CPU0
  DY87  PE3_TX_DN2  OUT  = P5E_CPU0_PE3_TX_DN<2>
  DY89  VCCFA_EHV_FIVRA66  POWER  = PVCCFA_EHV_FIVRA_CPU0
  DY91  PE3_RX_DN3  IN  = P5E_CPU0_PE3_RX_DN<3>
  E5  VSS1125  POWER  = GND
  E7  DDR0_SB_DQ31  BI  = M_A_CPU0_SB_DQ<31>
  E9  DDR0_SB_DQS_DP8  BI  = M_A_CPU0_SB_DQS_DP<8>
  E11  DDR0_SB_DQ26  BI  = M_A_CPU0_SB_DQ<26>
  E13  DDR1_SB_DQ29  BI  = M_B_CPU0_SB_DQ<29>
  E15  DDR1_SB_DQS_DN8  BI  = M_B_CPU0_SB_DQS_DN<8>
  E17  DDR1_SB_DQ26  BI  = M_B_CPU0_SB_DQ<26>
  E19  DDR0_SB_DQ23  BI  = M_A_CPU0_SB_DQ<23>
  E21  DDR0_SB_DQS_DP7  BI  = M_A_CPU0_SB_DQS_DP<7>
  E23  DDR0_SB_DQ18  BI  = M_A_CPU0_SB_DQ<18>
  E25  DDR0_SB_DQ15  BI  = M_A_CPU0_SB_DQ<15>
  E27  DDR0_SB_DQS_DP6  BI  = M_A_CPU0_SB_DQS_DP<6>
  E29  DDR0_SB_DQ10  BI  = M_A_CPU0_SB_DQ<10>
  E31  DDR0_SB_ECC3  BI  = M_A_CPU0_SB_CB<3>
  E33  DDR0_SB_DQS_DP4  BI  = M_A_CPU0_SB_DQS_DP<4>
  E35  DDR0_SB_ECC6  BI  = M_A_CPU0_SB_CB<6>
  E37  DDR0_SB_CS_N3  OUT  = M_A_CPU0_SB_CS_N<3>
  E39  VSS1271  POWER  = GND
  E41  DDR0_SB_CA3  OUT  = M_A_CPU0_SB_CA<3>
  E43  DDR0_SB_CA0  OUT  = M_A_CPU0_SB_CA<0>
  E45  DDR0_CLK_DP1  OUT  = M_A_CPU0_CLK_DP<1>
  E48  DDR0_SA_PAR  OUT  = M_A_CPU0_SA_PAR
  E50  DDR0_SA_CA5  OUT  = M_A_CPU0_SA_CA<5>
  E52  VSS1126  POWER  = GND
  E54  DDR0_SA_CS_N2  OUT  = M_A_CPU0_SA_CS_N<2>
  E56  DDR0_SA_ECC7  BI  = M_A_CPU0_SA_CB<7>
  E58  DDR0_SA_DQS_DP9  BI  = M_A_CPU0_SA_DQS_DP<9>
  E60  DDR0_SA_ECC2  BI  = M_A_CPU0_SA_CB<2>
  E62  DDR0_SA_DQ31  BI  = M_A_CPU0_SA_DQ<31>
  E64  DDR0_SA_DQS_DP8  BI  = M_A_CPU0_SA_DQS_DP<8>
  E66  DDR0_SA_DQ26  BI  = M_A_CPU0_SA_DQ<26>
  E68  DDR0_SA_DQ23  BI  = M_A_CPU0_SA_DQ<23>
  E70  DDR0_SA_DQS_DP7  BI  = M_A_CPU0_SA_DQS_DP<7>
  E72  DDR0_SA_DQ17  BI  = M_A_CPU0_SA_DQ<17>
  E74  VSS1129  POWER  = GND
  E76  VSS1272  POWER  = GND
  E78  VSS1131  POWER  = GND
  E80  UPI2_RX_DN0  IN  = UPI_CPU1_CPU0_P2P2_DN<23>
  E82  UPI2_RX_DP1  IN  = UPI_CPU1_CPU0_P2P2_DN<22>
  E84  UPI2_TX_DN1  OUT  = UPI_CPU0_CPU1_P2P2_DN<22>
  E86  VSS1273  POWER  = GND
  E88  UPI2_TX_DP2  OUT  = UPI_CPU0_CPU1_P2P2_DP<21>
  EA1  UPI1_RX_DN3  IN  = UPI_CPU1_CPU0_P0P1_DN<3>
  EA3  VCCFA_EHV_FIVRA69  POWER  = PVCCFA_EHV_FIVRA_CPU0
  EA5  UPI1_TX_DP2  OUT  = UPI_CPU0_CPU1_P1P0_DP<2>
  EA7  VCCFA_EHV_FIVRA70  POWER  = PVCCFA_EHV_FIVRA_CPU0
  EA9  PE2_RX_DN12  IN  = P5E_CPU0_PE2_RX_DN<12>
  EA11  VCCFA_EHV_FIVRA67  POWER  = PVCCFA_EHV_FIVRA_CPU0
  EA13  PE2_TX_DN12  OUT  = P5E_CPU0_PE2_TX_DN<12>
  EA15  VCCFA_EHV_FIVRA68  POWER  = PVCCFA_EHV_FIVRA_CPU0
  EA17  DDR5_SB_DQ28  BI  = M_F_CPU0_SB_DQ<28>
  EA19  DDR5_SB_DQ27  BI  = M_F_CPU0_SB_DQ<27>
  EA21  VSS1274  POWER  = GND
  EA23  DDR6_SB_DQ22  BI  = M_G_CPU0_SB_DQ<22>
  EA25  DDR6_SB_DQ19  BI  = M_G_CPU0_SB_DQ<19>
  EA27  VSS1275  POWER  = GND
  EA29  DDR5_SB_DQ6  BI  = M_F_CPU0_SB_DQ<6>
  EA31  DDR5_SB_DQ3  BI  = M_F_CPU0_SB_DQ<3>
  EA33  VSS1278  POWER  = GND
  EA35  DDR6_SB_ECC2  BI  = M_G_CPU0_SB_CB<2>
  EA37  DDR6_SB_ECC7  BI  = M_G_CPU0_SB_CB<7>
  EA39  VSS1141  POWER  = GND
  EA41  DDR6_SB_CS_N0  OUT  = M_G_CPU0_SB_CS_N<0>
  EA43  DDR6_SB_CA5  OUT  = M_G_CPU0_SB_CA<5>
  EA45  VSS1142  POWER  = GND
  EA48  DDR6_A_RSP0  IN  = M_G_CPU0_SA_RSP<0>
  EA50  DDR5_SA_PAR  OUT  = M_F_CPU0_SA_PAR
  EA52  VSS1144  POWER  = GND
  EA54  DDR5_SA_DQ30  BI  = M_F_CPU0_SA_DQ<30>
  EA56  DDR5_SA_DQ27  BI  = M_F_CPU0_SA_DQ<27>
  EA58  VSS1145  POWER  = GND
  EA60  DDR6_SA_DQ22  BI  = M_G_CPU0_SA_DQ<22>
  EA62  DDR6_SA_DQ19  BI  = M_G_CPU0_SA_DQ<19>
  EA64  VSS1146  POWER  = GND
  EA66  DDR5_SA_DQ14  BI  = M_F_CPU0_SA_DQ<14>
  EA68  DDR5_SA_DQ11  BI  = M_F_CPU0_SA_DQ<11>
  EA70  VSS1279  POWER  = GND
  EA72  DDR6_SA_DQ6  BI  = M_G_CPU0_SA_DQ<6>
  EA74  DDR6_SA_DQ3  BI  = M_G_CPU0_SA_DQ<3>
  EA76  VSS1280  POWER  = GND
  EA78  VSS1281  POWER  = GND
  EA80  VSS1282  POWER  = GND
  EA82  UPI3_RX_DN7  IN  = GND
  EA84  VSS1285  POWER  = GND
  EA86  PE3_TX_DP2  OUT  = P5E_CPU0_PE3_TX_DP<2>
  EA88  VSS1286  POWER  = GND
  EA90  PE3_RX_DP3  IN  = P5E_CPU0_PE3_RX_DP<3>
  EB2  UPI1_RX_DP3  IN  = UPI_CPU1_CPU0_P0P1_DP<3>
  EB4  VSS1163  POWER  = GND
  EB6  UPI1_TX_DN2  OUT  = UPI_CPU0_CPU1_P1P0_DN<2>
  EB8  VSS1306  POWER  = GND
  EB10  PE2_RX_DP12  IN  = P5E_CPU0_PE2_RX_DP<12>
  EB12  VSS1287  POWER  = GND
  EB14  PE2_TX_DN13  OUT  = P5E_CPU0_PE2_TX_DN<13>
  EB16  VSS1155  POWER  = GND
  EB18  DDR5_SB_DQS_DP8  BI  = M_F_CPU0_SB_DQS_DP<8>
  EB20  VSS1156  POWER  = GND
  EB22  VSS1288  POWER  = GND
  EB24  DDR6_SB_DQS_DN7  BI  = M_G_CPU0_SB_DQS_DN<7>
  EB26  VSS1158  POWER  = GND
  EB28  VSS1289  POWER  = GND
  EB30  DDR5_SB_DQS_DN5  BI  = M_F_CPU0_SB_DQS_DN<5>
  EB32  VSS1292  POWER  = GND
  EB34  VSS1161  POWER  = GND
  EB36  DDR6_SB_DQS_DN4  BI  = M_G_CPU0_SB_DQS_DN<4>
  EB38  VSS1293  POWER  = GND
  EB40  VSS1295  POWER  = GND
  EB42  DDR6_SB_PAR  OUT  = M_G_CPU0_SB_PAR
  EB44  VSS1165  POWER  = GND
  EB47  VSS1296  POWER  = GND
  EB49  DDR5_CLK_DP0  OUT  = M_F_CPU0_CLK_DP<0>
  EB51  VSS1167  POWER  = GND
  EB53  VSS1168  POWER  = GND
  EB55  DDR5_SA_DQS_DN8  BI  = M_F_CPU0_SA_DQS_DN<8>
  EB57  VSS1297  POWER  = GND
  EB59  VSS1170  POWER  = GND
  EB61  DDR6_SA_DQS_DN7  BI  = M_G_CPU0_SA_DQS_DN<7>
  EB63  VSS1171  POWER  = GND
  EB65  VSS1298  POWER  = GND
  EB67  DDR5_SA_DQS_DN6  BI  = M_F_CPU0_SA_DQS_DN<6>
  EB69  VSS1299  POWER  = GND
  EB71  VSS1300  POWER  = GND
  EB73  DDR6_SA_DQS_DN5  BI  = M_G_CPU0_SA_DQS_DN<5>
  EB75  VSS1301  POWER  = GND
  EB77  DDR5_SA_DQ0  BI  = M_F_CPU0_SA_DQ<0>
  EB79  VSS1304  POWER  = GND
  EB81  UPI3_RX_DP8  IN  = GND
  EB83  VSS1307  POWER  = GND
  EB85  PE3_TX_DN1  OUT  = P5E_CPU0_PE3_TX_DN<1>
  EB87  VSS1308  POWER  = GND
  EB89  PE3_RX_DP2  IN  = P5E_CPU0_PE3_RX_DP<2>
  EB91  VSS1180  POWER  = GND
  EC1  VSS1309  POWER  = GND
  EC3  UPI1_RX_DP2  IN  = UPI_CPU1_CPU0_P0P1_DN<2>
  EC5  VSS1193  POWER  = GND
  EC7  UPI1_TX_DN1  OUT  = UPI_CPU0_CPU1_P1P0_DN<1>
  EC9  VSS1337  POWER  = GND
  EC11  PE2_RX_DP13  IN  = P5E_CPU0_PE2_RX_DP<13>
  EC13  VSS1310  POWER  = GND
  EC15  PE2_TX_DP13  OUT  = P5E_CPU0_PE2_TX_DP<13>
  EC17  DDR5_SB_DQ30  BI  = M_F_CPU0_SB_DQ<30>
  EC19  VSS1311  POWER  = GND
  EC21  DDR5_SB_DQS_DP1  BI  = M_F_CPU0_SB_DQS_DP<1>
  EC23  VSS1313  POWER  = GND
  EC25  VSS1185  POWER  = GND
  EC27  DDR4_SB_DQS_DP0  BI  = M_E_CPU0_SB_DQS_DP<0>
  EC29  VSS1314  POWER  = GND
  EC31  VSS1316  POWER  = GND
  EC33  DDR5_SB_DQS_DP9  BI  = M_F_CPU0_SB_DQS_DP<9>
  EC35  VSS1188  POWER  = GND
  EC37  VSS1317  POWER  = GND
  EC39  DDR5_SB_CA6  OUT  = M_F_CPU0_SB_CA<6>
  EC41  VSS1321  POWER  = GND
  EC43  VSS1323  POWER  = GND
  EC45  DDR4_CLK_DP1  OUT  = M_E_CPU0_CLK_DP<1>
  EC48  VSS1324  POWER  = GND
  EC50  VSS1326  POWER  = GND
  EC52  DDR5_SA_CA0  OUT  = M_F_CPU0_SA_CA<0>
  EC54  VSS1195  POWER  = GND
  EC56  VSS1327  POWER  = GND
  EC58  DDR5_SA_DQS_DP4  BI  = M_F_CPU0_SA_DQS_DP<4>
  EC60  VSS1197  POWER  = GND
  EC62  VSS1198  POWER  = GND
  EC64  DDR5_SA_DQS_DN2  BI  = M_F_CPU0_SA_DQS_DN<2>
  EC66  VSS1329  POWER  = GND
  EC68  VSS1200  POWER  = GND
  EC70  DDR4_SA_DQS_DN1  BI  = M_E_CPU0_SA_DQS_DN<1>
  EC72  VSS1330  POWER  = GND
  EC74  VSS1332  POWER  = GND
  EC76  DDR5_SA_DQS_DP0  BI  = M_F_CPU0_SA_DQS_DP<0>
  EC78  VCCFA_EHV_FIVRA71  POWER  = PVCCFA_EHV_FIVRA_CPU0
  EC80  UPI3_RX_DN6  IN  = GND
  EC82  VSS1333  POWER  = GND
  EC84  VSS1335  POWER  = GND
  EC86  PE3_TX_DP1  OUT  = P5E_CPU0_PE3_TX_DP<1>
  EC88  VSS1336  POWER  = GND
  EC90  PE3_RX_DN2  IN  = P5E_CPU0_PE3_RX_DN<2>
  ED2  UPI1_RX_DN2  IN  = UPI_CPU1_CPU0_P0P1_DP<2>
  ED4  VSS1344  POWER  = GND
  ED6  UPI1_TX_DP1  OUT  = UPI_CPU0_CPU1_P1P0_DP<1>
  ED8  VSS1348  POWER  = GND
  ED10  PE2_RX_DN13  IN  = P5E_CPU0_PE2_RX_DN<13>
  ED12  VSS1208  POWER  = GND
  ED14  PE2_TX_DP14  OUT  = P5E_CPU0_PE2_TX_DP<14>
  ED16  VSS1338  POWER  = GND
  ED18  VSS1210  POWER  = GND
  ED20  DDR5_SB_DQ12  BI  = M_F_CPU0_SB_DQ<12>
  ED22  DDR5_SB_DQ9  BI  = M_F_CPU0_SB_DQ<9>
  ED24  VSS1339  POWER  = GND
  ED26  DDR4_SB_DQ4  BI  = M_E_CPU0_SB_DQ<4>
  ED28  DDR4_SB_DQ1  BI  = M_E_CPU0_SB_DQ<1>
  ED30  VSS1341  POWER  = GND
  ED32  DDR5_SB_ECC0  BI  = M_F_CPU0_SB_CB<0>
  ED34  DDR5_SB_ECC5  BI  = M_F_CPU0_SB_CB<5>
  ED36  VSS1342  POWER  = GND
  ED38  DDR5_SB_CS_N2  OUT  = M_F_CPU0_SB_CS_N<2>
  ED40  DDR5_SB_CA4  OUT  = M_F_CPU0_SB_CA<4>
  ED42  VSS1217  POWER  = GND
  ED44  DDR4_SA_CA6  OUT  = M_E_CPU0_SA_CA<6>
  ED47  DDR7_B_RSP1  IN  = M_H_CPU0_SB_RSP<1>
  ED49  VSS1346  POWER  = GND
  ED51  DDR5_SA_CA2  OUT  = M_F_CPU0_SA_CA<2>
  ED53  DDR5_SA_CS_N3  OUT  = M_F_CPU0_SA_CS_N<3>
  ED55  VSS1220  POWER  = GND
  ED57  DDR5_SA_ECC4  BI  = M_F_CPU0_SA_CB<4>
  ED59  DDR5_SA_ECC1  BI  = M_F_CPU0_SA_CB<1>
  ED61  VSS1223  POWER  = GND
  ED63  DDR5_SA_DQ20  BI  = M_F_CPU0_SA_DQ<20>
  ED65  DDR5_SA_DQ17  BI  = M_F_CPU0_SA_DQ<17>
  ED67  VSS1224  POWER  = GND
  ED69  DDR4_SA_DQ12  BI  = M_E_CPU0_SA_DQ<12>
  ED71  DDR4_SA_DQ9  BI  = M_E_CPU0_SA_DQ<9>
  ED73  VSS1225  POWER  = GND
  ED75  DDR5_SA_DQ4  BI  = M_F_CPU0_SA_DQ<4>
  ED77  DDR5_SA_DQ2  BI  = M_F_CPU0_SA_DQ<2>
  ED79  VCCFA_EHV_FIVRA72  POWER  = PVCCFA_EHV_FIVRA_CPU0
  ED81  UPI3_RX_DP6  IN  = GND
  ED83  UPI3_RX_DN5  IN  = GND
  ED85  VCCFA_EHV_FIVRA73  POWER  = PVCCFA_EHV_FIVRA_CPU0
  ED87  PE3_TX_DP0  OUT  = P5E_CPU0_PE3_TX_DP<0>
  ED89  VCCFA_EHV_FIVRA74  POWER  = PVCCFA_EHV_FIVRA_CPU0
  ED91  PE3_RX_DN1  IN  = P5E_CPU0_PE3_RX_DN<1>
  EE3  UPI1_RX_DN1  IN  = UPI_CPU1_CPU0_P0P1_DN<1>
  EE5  UPI1_TX_DP0  OUT  = UPI_CPU0_CPU1_P1P0_DP<0>
  EE7  VCCFA_EHV_FIVRA77  POWER  = PVCCFA_EHV_FIVRA_CPU0
  EE9  PE2_RX_DN14  IN  = P5E_CPU0_PE2_RX_DN<14>
  EE11  VCCFA_EHV_FIVRA75  POWER  = PVCCFA_EHV_FIVRA_CPU0
  EE13  PE2_TX_DN14  OUT  = P5E_CPU0_PE2_TX_DN<14>
  EE15  VCCFA_EHV_FIVRA76  POWER  = PVCCFA_EHV_FIVRA_CPU0
  EE17  VSS1232  POWER  = GND
  EE19  DDR5_SB_DQ13  BI  = M_F_CPU0_SB_DQ<13>
  EE21  DDR5_SB_DQS_DN1  BI  = M_F_CPU0_SB_DQS_DN<1>
  EE23  DDR5_SB_DQ8  BI  = M_F_CPU0_SB_DQ<8>
  EE25  DDR4_SB_DQ5  BI  = M_E_CPU0_SB_DQ<5>
  EE27  DDR4_SB_DQS_DN0  BI  = M_E_CPU0_SB_DQS_DN<0>
  EE29  DDR4_SB_DQ0  BI  = M_E_CPU0_SB_DQ<0>
  EE31  DDR5_SB_ECC1  BI  = M_F_CPU0_SB_CB<1>
  EE33  DDR5_SB_DQS_DN9  BI  = M_F_CPU0_SB_DQS_DN<9>
  EE35  DDR5_SB_ECC4  BI  = M_F_CPU0_SB_CB<4>
  EE37  DDR5_SB_CS_N3  OUT  = M_F_CPU0_SB_CS_N<3>
  EE39  VSS1235  POWER  = GND
  EE41  DDR5_SB_CA2  OUT  = M_F_CPU0_SB_CA<2>
  EE43  DDR4_SA_PAR  OUT  = M_E_CPU0_SA_PAR
  EE45  DDR4_CLK_DN1  OUT  = M_E_CPU0_CLK_DN<1>
  EE48  DDR7_B_RSP0  IN  = M_H_CPU0_SB_RSP<0>
  EE50  DDR5_SA_CA4  OUT  = M_F_CPU0_SA_CA<4>
  EE52  VSS1237  POWER  = GND
  EE54  DDR5_SA_CS_N2  OUT  = M_F_CPU0_SA_CS_N<2>
  EE56  DDR5_SA_ECC5  BI  = M_F_CPU0_SA_CB<5>
  EE58  DDR5_SA_DQS_DN4  BI  = M_F_CPU0_SA_DQS_DN<4>
  EE60  DDR5_SA_ECC0  BI  = M_F_CPU0_SA_CB<0>
  EE62  DDR5_SA_DQ21  BI  = M_F_CPU0_SA_DQ<21>
  EE64  DDR5_SA_DQS_DP2  BI  = M_F_CPU0_SA_DQS_DP<2>
  EE66  DDR5_SA_DQ16  BI  = M_F_CPU0_SA_DQ<16>
  EE68  DDR4_SA_DQ13  BI  = M_E_CPU0_SA_DQ<13>
  EE70  DDR4_SA_DQS_DP1  BI  = M_E_CPU0_SA_DQS_DP<1>
  EE72  DDR4_SA_DQ8  BI  = M_E_CPU0_SA_DQ<8>
  EE74  DDR5_SA_DQ5  BI  = M_F_CPU0_SA_DQ<5>
  EE76  DDR5_SA_DQS_DN0  BI  = M_F_CPU0_SA_DQS_DN<0>
  EE78  VSS1349  POWER  = GND
  EE80  VSS1350  POWER  = GND
  EE82  UPI3_RX_DP4  IN  = GND
  EE84  VCCFA_EHV_FIVRA78  POWER  = PVCCFA_EHV_FIVRA_CPU0
  EE86  PE3_TX_DN0  OUT  = P5E_CPU0_PE3_TX_DN<0>
  EE88  VSS1351  POWER  = GND
  EE90  PE3_RX_DP1  IN  = P5E_CPU0_PE3_RX_DP<1>
  EF2  VSS1356  POWER  = GND
  EF4  VSS1374  POWER  = GND
  EF6  UPI1_TX_DN0  OUT  = UPI_CPU0_CPU1_P1P0_DN<0>
  EF8  VSS1404  POWER  = GND
  EF10  PE2_RX_DP14  IN  = P5E_CPU0_PE2_RX_DP<14>
  EF12  VSS1352  POWER  = GND
  EF14  PE2_TX_DN15  OUT  = P5E_CPU0_PE2_TX_DN<15>
  EF16  VSS1353  POWER  = GND
  EF18  VSS1354  POWER  = GND
  EF20  VSS1358  POWER  = GND
  EF22  VSS1360  POWER  = GND
  EF24  VSS1361  POWER  = GND
  EF26  VSS1362  POWER  = GND
  EF28  VSS1363  POWER  = GND
  EF30  VSS1364  POWER  = GND
  EF32  VSS1365  POWER  = GND
  EF34  VSS1367  POWER  = GND
  EF36  VSS1370  POWER  = GND
  EF38  VSS1373  POWER  = GND
  EF40  VSS1376  POWER  = GND
  EF42  VSS1382  POWER  = GND
  EF44  VSS1383  POWER  = GND
  EF47  VSS1384  POWER  = GND
  EF49  VSS1385  POWER  = GND
  EF51  VSS1265  POWER  = GND
  EF53  VSS1386  POWER  = GND
  EF55  VSS1387  POWER  = GND
  EF57  VSS1388  POWER  = GND
  EF59  VSS1389  POWER  = GND
  EF61  VSS1390  POWER  = GND
